G04*
G04 #@! TF.GenerationSoftware,Altium Limited,Altium Designer,22.4.2 (48)*
G04*
G04 Layer_Color=0*
%FSLAX25Y25*%
%MOIN*%
G70*
G04*
G04 #@! TF.SameCoordinates,B69760C6-9901-4916-8BAC-4CFDAA04743E*
G04*
G04*
G04 #@! TF.FilePolarity,Positive*
G04*
G01*
G75*
%ADD61C,0.00100*%
G36*
X243311Y113764D02*
Y113163D01*
X243546Y111984D01*
X244005Y110873D01*
X244673Y109874D01*
X245523Y109024D01*
X246523Y108356D01*
X247633Y107896D01*
X248812Y107661D01*
X249413D01*
X250014D01*
X251193Y107896D01*
X252304Y108356D01*
X253303Y109024D01*
X254153Y109874D01*
X254821Y110873D01*
X255281Y111984D01*
X255516Y113163D01*
Y113764D01*
Y114365D01*
X255281Y115544D01*
X254821Y116654D01*
X254153Y117654D01*
X253303Y118504D01*
X252304Y119172D01*
X251193Y119632D01*
X250014Y119866D01*
X249413D01*
X248812D01*
X247633Y119632D01*
X246523Y119172D01*
X245523Y118504D01*
X244673Y117654D01*
X244005Y116654D01*
X243546Y115544D01*
X243311Y114365D01*
Y113764D01*
D01*
D02*
G37*
G36*
Y11402D02*
Y10801D01*
X243546Y9622D01*
X244005Y8511D01*
X244673Y7512D01*
X245523Y6662D01*
X246523Y5994D01*
X247633Y5534D01*
X248812Y5299D01*
X249413D01*
X250014D01*
X251193Y5534D01*
X252304Y5994D01*
X253303Y6662D01*
X254153Y7512D01*
X254821Y8511D01*
X255281Y9622D01*
X255516Y10801D01*
Y11402D01*
Y12003D01*
X255281Y13182D01*
X254821Y14292D01*
X254153Y15292D01*
X253303Y16142D01*
X252304Y16809D01*
X251193Y17269D01*
X250014Y17504D01*
X249413D01*
X248812D01*
X247633Y17269D01*
X246523Y16809D01*
X245523Y16142D01*
X244673Y15292D01*
X244005Y14292D01*
X243546Y13182D01*
X243311Y12003D01*
Y11402D01*
D01*
D02*
G37*
G36*
X5122D02*
Y10801D01*
X5357Y9622D01*
X5817Y8511D01*
X6484Y7512D01*
X7334Y6662D01*
X8334Y5994D01*
X9444Y5534D01*
X10623Y5299D01*
X11224D01*
X11825D01*
X13004Y5534D01*
X14115Y5994D01*
X15114Y6662D01*
X15964Y7512D01*
X16632Y8511D01*
X17092Y9622D01*
X17327Y10801D01*
Y11402D01*
Y12003D01*
X17092Y13182D01*
X16632Y14292D01*
X15964Y15292D01*
X15114Y16142D01*
X14115Y16809D01*
X13004Y17269D01*
X11825Y17504D01*
X11224D01*
X10623D01*
X9444Y17269D01*
X8334Y16809D01*
X7334Y16142D01*
X6484Y15292D01*
X5817Y14292D01*
X5357Y13182D01*
X5122Y12003D01*
Y11402D01*
D01*
D02*
G37*
G36*
X11224Y107661D02*
X10623D01*
X9444Y107896D01*
X8334Y108356D01*
X7334Y109024D01*
X6484Y109874D01*
X5817Y110873D01*
X5357Y111984D01*
X5122Y113163D01*
Y113764D01*
Y114365D01*
X5357Y115544D01*
X5817Y116654D01*
X6484Y117654D01*
X7334Y118504D01*
X8334Y119172D01*
X9444Y119632D01*
X10623Y119866D01*
X11224D01*
X11825D01*
X13004Y119632D01*
X14115Y119172D01*
X15114Y118504D01*
X15964Y117654D01*
X16632Y116654D01*
X17092Y115544D01*
X17327Y114365D01*
Y113764D01*
Y113163D01*
X17092Y111984D01*
X16632Y110873D01*
X15964Y109874D01*
X15114Y109024D01*
X14115Y108356D01*
X13004Y107896D01*
X11825Y107661D01*
X11224D01*
D01*
D02*
G37*
D61*
X0Y4114D02*
G03*
X4114Y0I4114J0D01*
G01*
X260445Y-16D01*
D02*
G03*
X264453Y3996I-4J4012D01*
G01*
X264465Y120748D01*
D02*
G03*
X260213Y124996I-4252J-4D01*
G01*
X4205Y124988D01*
D02*
G03*
X-8Y120772I4J-4216D01*
G01*
X0Y4114D01*
M02*
